# T6G (Grand Teton) — schematic netlist excerpt (pin names and nets, part order shuffled) for the footprints in the layout excerpt that follows; sources: Cadence DE-HDL packaged netlist, KiCad conversion of 04192023_DAF0TMB3IC0_F0TG_MB_C_brd_V02_OCP.brd

R6179  Q_RES  1K 1% CHIP  pkg 0402LF  page 112 : A = P3V3_AUX ; B = FM_P2E_BUF2_VOD_SEL

J57  CONN8_HBB1081L200D8H  CONN8_HBB1081-L200D-8H IO  pkg HEADER1X8XA_H340  page 85
  \1\  = P3V3_AUX
  \2\  = JTAG_PLD_TDI
  \3\  = JTAG_PLD_TDO
  \4\  = NC
  \5\  = NC
  \6\  = JTAG_PLD_TMS
  \7\  = GND
  \8\  = JTAG_PLD_TCK

(kicad_pcb
	(version 20260206)
	(generator "pcbnew")
	(generator_version "10.0")
	(general
		(thickness 1.6)
		(legacy_teardrops no)
	)
	(paper "A4")
	(title_block
		(title "04192023_DAF0TMB3IC0_F0TG_MB_C_brd_V02_OCP.brd")
		(comment 1 "Grand Teton / footprints 2307-2308 of 8354")
	)
	(layers
		(0 "F.Cu" signal "TOP")
		(4 "In1.Cu" signal "GND")
		(6 "In2.Cu" signal "IN1")
		(8 "In3.Cu" signal "GND1")
		(10 "In4.Cu" signal "IN2")
		(12 "In5.Cu" signal "GND2")
		(14 "In6.Cu" signal "IN3")
		(16 "In7.Cu" signal "GND3")
		(18 "In8.Cu" signal "VCC")
		(20 "In9.Cu" signal "VCC1")
		(22 "In10.Cu" signal "GND4")
		(24 "In11.Cu" signal "IN4")
		(26 "In12.Cu" signal "GND5")
		(28 "In13.Cu" signal "IN5")
		(30 "In14.Cu" signal "GND6")
		(32 "In15.Cu" signal "IN6")
		(34 "In16.Cu" signal "GND7")
		(2 "B.Cu" signal "BOTTOM")
		(9 "F.Adhes" user "F.Adhesive")
		(11 "B.Adhes" user "B.Adhesive")
		(13 "F.Paste" user "Package Geometry/Pastemask Top")
		(15 "B.Paste" user "Package Geometry/Pastemask Bottom")
		(5 "F.SilkS" user "Ref Des/Silkscreen Top")
		(7 "B.SilkS" user "Ref Des/Silkscreen Bottom")
		(1 "F.Mask" user "Board Geometry/Soldermask Top")
		(3 "B.Mask" user "Board Geometry/Soldermask Bottom")
		(17 "Dwgs.User" user "User.Drawings")
		(19 "Cmts.User" user "User.Comments")
		(21 "Eco1.User" user "User.Eco1")
		(23 "Eco2.User" user "User.Eco2")
		(25 "Edge.Cuts" user "Board Geometry/Outline")
		(27 "Margin" user)
		(31 "F.CrtYd" user "Package Geometry/Place Bound Top")
		(29 "B.CrtYd" user "Package Geometry/Place Bound Bottom")
		(35 "F.Fab" user "Ref Des/Assembly Top")
		(33 "B.Fab" user "Ref Des/Assembly Bottom")
	)
	(footprint ""
		(layer "F.Cu")
		(at 154.690064 -69.665088 -90)
		(property "Reference" "J57"
			(at 2.393696 1.000252 0)
			(unlocked yes)
			(layer "F.SilkS")
			(effects
				(font
					(size 0.7874 0.5842)
					(thickness 0.1524)
				)
				(justify left)
			)
		)
		(property "Value" ""
			(at 0 0 270)
			(layer "F.Fab")
			(effects
				(font
					(size 1.27 1.27)
				)
			)
		)
		(duplicate_pad_numbers_are_jumpers no)
		(fp_line
			(start -1.234948 19.05)
			(end -1.234948 -1.27)
			(stroke
				(width 0.1524)
				(type default)
			)
			(layer "F.SilkS")
		)
		(fp_line
			(start 1.234948 19.05)
			(end -1.234948 19.05)
			(stroke
				(width 0.1524)
				(type default)
			)
			(layer "F.SilkS")
		)
		(fp_line
			(start -1.234948 -1.27)
			(end 1.234948 -1.27)
			(stroke
				(width 0.1524)
				(type default)
			)
			(layer "F.SilkS")
		)
		(fp_line
			(start 1.234948 -1.27)
			(end 1.234948 19.05)
			(stroke
				(width 0.1524)
				(type default)
			)
			(layer "F.SilkS")
		)
		(fp_poly
			(pts
				(xy -2.8194 0.635) (xy -2.8194 -0.5842) (xy -1.4986 0)
			)
			(stroke
				(width 0)
				(type default)
			)
			(fill yes)
			(layer "F.SilkS")
		)
		(fp_line
			(start -1.23698 19.05)
			(end -1.23698 -1.27)
			(stroke
				(width 0.1)
				(type default)
			)
			(layer "F.Fab")
		)
		(fp_line
			(start 1.23698 19.05)
			(end -1.23698 19.05)
			(stroke
				(width 0.1)
				(type default)
			)
			(layer "F.Fab")
		)
		(fp_line
			(start -1.23698 -1.27)
			(end 1.23698 -1.27)
			(stroke
				(width 0.1)
				(type default)
			)
			(layer "F.Fab")
		)
		(fp_line
			(start 1.23698 -1.27)
			(end 1.23698 19.05)
			(stroke
				(width 0.1)
				(type default)
			)
			(layer "F.Fab")
		)
		(fp_poly
			(pts
				(xy -1.4986 0) (xy -2.8194 -0.5842) (xy -2.8194 0.635)
			)
			(stroke
				(width 0)
				(type default)
			)
			(fill yes)
			(layer "F.Fab")
		)
		(fp_text user "8"
			(at -1.886966 18.1737 0)
			(unlocked yes)
			(layer "F.SilkS")
			(effects
				(font
					(size 0.7874 0.5842)
					(thickness 0.1524)
				)
				(justify left)
			)
		)
		(fp_text user "8"
			(at -0.085852 19.3421 180)
			(unlocked yes)
			(layer "B.SilkS")
			(effects
				(font
					(size 0.7874 0.5842)
					(thickness 0.1524)
				)
				(justify left mirror)
			)
		)
		(fp_text user "1"
			(at 0.015748 -0.9271 180)
			(unlocked yes)
			(layer "B.SilkS")
			(effects
				(font
					(size 0.7874 0.5842)
					(thickness 0.1524)
				)
				(justify left mirror)
			)
		)
		(fp_text user "8"
			(at -0.085852 19.3421 180)
			(unlocked yes)
			(layer "B.Fab")
			(effects
				(font
					(size 0.7874 0.5842)
					(thickness 0.1524)
				)
				(justify left mirror)
			)
		)
		(fp_text user "1"
			(at 0.015748 -0.9271 180)
			(unlocked yes)
			(layer "B.Fab")
			(effects
				(font
					(size 0.7874 0.5842)
					(thickness 0.1524)
				)
				(justify left mirror)
			)
		)
		(fp_text user "8"
			(at -1.965706 17.5895 180)
			(unlocked yes)
			(layer "F.Fab")
			(effects
				(font
					(size 0.7874 0.5842)
					(thickness 0.1524)
				)
				(justify left)
			)
		)
		(pad "1" thru_hole rect
			(at 0 0 180)
			(size 1.6764 1.6764)
			(drill 1.1684)
			(layers "*.Cu" "*.Mask")
			(remove_unused_layers no)
			(net "P3V3_AUX")
			(clearance 0)
			(padstack
				(mode front_inner_back)
				(layer "Inner"
					(shape circle)
					(size 1.6764 1.6764)
					(clearance 0)
				)
				(layer "B.Cu"
					(shape rect)
					(size 1.6764 1.6764)
					(clearance 0)
				)
			)
		)
		(pad "2" thru_hole circle
			(at 0 2.54 180)
			(size 1.6764 1.6764)
			(drill 1.1684)
			(layers "*.Cu" "*.Mask")
			(remove_unused_layers no)
			(net "JTAG_PLD_TDI")
			(clearance 0)
		)
		(pad "3" thru_hole circle
			(at 0 5.08 180)
			(size 1.6764 1.6764)
			(drill 1.1684)
			(layers "*.Cu" "*.Mask")
			(remove_unused_layers no)
			(net "JTAG_PLD_TDO")
			(clearance 0)
		)
		(pad "4" thru_hole circle
			(at 0 7.62 180)
			(size 1.6764 1.6764)
			(drill 1.1684)
			(layers "*.Cu" "*.Mask")
			(remove_unused_layers no)
			(net "Net_10747")
			(clearance 0)
		)
		(pad "5" thru_hole circle
			(at 0 10.16 180)
			(size 1.6764 1.6764)
			(drill 1.1684)
			(layers "*.Cu" "*.Mask")
			(remove_unused_layers no)
			(net "Net_10746")
			(clearance 0)
		)
		(pad "6" thru_hole circle
			(at 0 12.7 180)
			(size 1.6764 1.6764)
			(drill 1.1684)
			(layers "*.Cu" "*.Mask")
			(remove_unused_layers no)
			(net "JTAG_PLD_TMS")
			(clearance 0)
		)
		(pad "7" thru_hole circle
			(at 0 15.24 180)
			(size 1.6764 1.6764)
			(drill 1.1684)
			(layers "*.Cu" "*.Mask")
			(remove_unused_layers no)
			(net "GND")
			(clearance 0)
		)
		(pad "8" thru_hole circle
			(at 0 17.78 180)
			(size 1.6764 1.6764)
			(drill 1.1684)
			(layers "*.Cu" "*.Mask")
			(remove_unused_layers no)
			(net "JTAG_PLD_TCK")
			(clearance 0)
		)
	)
	(footprint ""
		(layer "F.Cu")
		(at 16.364458 -418.690298 90)
		(property "Reference" "R6179"
			(at 0 0 90)
			(layer "F.SilkS")
			(hide yes)
			(effects
				(font
					(size 1.27 1.27)
				)
			)
		)
		(property "Value" ""
			(at 0 0 90)
			(layer "F.Fab")
			(effects
				(font
					(size 1.27 1.27)
				)
			)
		)
		(duplicate_pad_numbers_are_jumpers no)
		(fp_line
			(start 0.7874 -0.4064)
			(end 0.7874 0.4064)
			(stroke
				(width 0.1524)
				(type default)
			)
			(layer "F.SilkS")
		)
		(fp_line
			(start -0.7874 -0.4064)
			(end 0.7874 -0.4064)
			(stroke
				(width 0.1524)
				(type default)
			)
			(layer "F.SilkS")
		)
		(fp_line
			(start 0.7874 0.4064)
			(end -0.7874 0.4064)
			(stroke
				(width 0.1524)
				(type default)
			)
			(layer "F.SilkS")
		)
		(fp_line
			(start -0.7874 0.4064)
			(end -0.7874 -0.4064)
			(stroke
				(width 0.1524)
				(type default)
			)
			(layer "F.SilkS")
		)
		(fp_line
			(start -0.12065 -0.305054)
			(end -0.12065 -0.2794)
			(stroke
				(width 0.1)
				(type default)
			)
			(layer "F.Fab")
		)
		(fp_line
			(start -0.67945 -0.305054)
			(end -0.12065 -0.305054)
			(stroke
				(width 0.1)
				(type default)
			)
			(layer "F.Fab")
		)
		(fp_line
			(start 0.67945 -0.3048)
			(end 0.67945 0.3048)
			(stroke
				(width 0.1)
				(type default)
			)
			(layer "F.Fab")
		)
		(fp_line
			(start 0.12065 -0.3048)
			(end 0.67945 -0.3048)
			(stroke
				(width 0.1)
				(type default)
			)
			(layer "F.Fab")
		)
		(fp_line
			(start 0.12065 -0.2794)
			(end 0.12065 -0.3048)
			(stroke
				(width 0.1)
				(type default)
			)
			(layer "F.Fab")
		)
		(fp_line
			(start -0.12065 -0.2794)
			(end 0.12065 -0.2794)
			(stroke
				(width 0.1)
				(type default)
			)
			(layer "F.Fab")
		)
		(fp_line
			(start 0.120396 0.2794)
			(end -0.12065 0.2794)
			(stroke
				(width 0.1)
				(type default)
			)
			(layer "F.Fab")
		)
		(fp_line
			(start -0.12065 0.2794)
			(end -0.12065 0.3048)
			(stroke
				(width 0.1)
				(type default)
			)
			(layer "F.Fab")
		)
		(fp_line
			(start 0.67945 0.3048)
			(end 0.120396 0.3048)
			(stroke
				(width 0.1)
				(type default)
			)
			(layer "F.Fab")
		)
		(fp_line
			(start 0.120396 0.3048)
			(end 0.120396 0.2794)
			(stroke
				(width 0.1)
				(type default)
			)
			(layer "F.Fab")
		)
		(fp_line
			(start -0.12065 0.3048)
			(end -0.67945 0.3048)
			(stroke
				(width 0.1)
				(type default)
			)
			(layer "F.Fab")
		)
		(fp_line
			(start -0.67945 0.3048)
			(end -0.67945 -0.305054)
			(stroke
				(width 0.1)
				(type default)
			)
			(layer "F.Fab")
		)
		(pad "1" smd circle
			(at -0.40005 0 90)
			(size 0 0)
			(layers "F.Cu" "F.Mask" "F.Paste")
			(net "P3V3_AUX")
		)
		(pad "2" smd circle
			(at 0.40005 0 90)
			(size 0 0)
			(layers "F.Cu" "F.Mask" "F.Paste")
			(net "FM_P2E_BUF2_VOD_SEL")
		)
	)
)
